# S9S_MB_2U (Grand Teton) — schematic netlist excerpt (pin names and nets, part order shuffled) for the footprints in the layout excerpt that follows; sources: Cadence DE-HDL packaged netlist, KiCad conversion of 03242023_DA0F0TMBIJ0_F0T_Motherboard_J_brd_V01_OCP.brd

D93  Q_LED  IC  pkg SMLF  page 252 : A = LED_RST_RSMRST_PLD_R_N ; C = LED_RST_RSMRST_PLD_R_N_D
R139  Q_RES  10K 1% EMPTY  pkg 0402LF  page 220 : A = FM_BMC_PWRBTN_N ; B = P3V3_AUX

(kicad_pcb
	(version 20260206)
	(generator "pcbnew")
	(generator_version "10.0")
	(general
		(thickness 1.6)
		(legacy_teardrops no)
	)
	(paper "A4")
	(title_block
		(title "03242023_DA0F0TMBIJ0_F0T_Motherboard_J_brd_V01_OCP.brd")
		(comment 1 "Grand Teton / footprints 4092-4093 of 6105")
	)
	(layers
		(0 "F.Cu" signal "TOP")
		(4 "In1.Cu" signal "GND")
		(6 "In2.Cu" signal "IN1")
		(8 "In3.Cu" signal "GND1")
		(10 "In4.Cu" signal "IN2")
		(12 "In5.Cu" signal "GND2")
		(14 "In6.Cu" signal "IN3")
		(16 "In7.Cu" signal "GND3")
		(18 "In8.Cu" signal "VCC")
		(20 "In9.Cu" signal "VCC1")
		(22 "In10.Cu" signal "GND4")
		(24 "In11.Cu" signal "IN4")
		(26 "In12.Cu" signal "GND5")
		(28 "In13.Cu" signal "IN5")
		(30 "In14.Cu" signal "GND6")
		(32 "In15.Cu" signal "IN6")
		(34 "In16.Cu" signal "GND7")
		(2 "B.Cu" signal "BOTTOM")
		(9 "F.Adhes" user "F.Adhesive")
		(11 "B.Adhes" user "B.Adhesive")
		(13 "F.Paste" user "Package Geometry/Pastemask Top")
		(15 "B.Paste" user "Package Geometry/Pastemask Bottom")
		(5 "F.SilkS" user "Ref Des/Silkscreen Top")
		(7 "B.SilkS" user "Ref Des/Silkscreen Bottom")
		(1 "F.Mask" user "Board Geometry/Soldermask Top")
		(3 "B.Mask" user "Board Geometry/Soldermask Bottom")
		(17 "Dwgs.User" user "User.Drawings")
		(19 "Cmts.User" user "User.Comments")
		(21 "Eco1.User" user "User.Eco1")
		(23 "Eco2.User" user "User.Eco2")
		(25 "Edge.Cuts" user "Board Geometry/Outline")
		(27 "Margin" user)
		(31 "F.CrtYd" user "Package Geometry/Place Bound Top")
		(29 "B.CrtYd" user "Package Geometry/Place Bound Bottom")
		(35 "F.Fab" user "Ref Des/Assembly Top")
		(33 "B.Fab" user "Ref Des/Assembly Bottom")
	)
	(footprint ""
		(layer "F.Cu")
		(at 319.668906 -26.651458 -90)
		(property "Reference" "R139"
			(at 0 0 270)
			(layer "F.SilkS")
			(hide yes)
			(effects
				(font
					(size 1.27 1.27)
				)
			)
		)
		(property "Value" ""
			(at 0 0 270)
			(layer "F.Fab")
			(effects
				(font
					(size 1.27 1.27)
				)
			)
		)
		(duplicate_pad_numbers_are_jumpers no)
		(fp_line
			(start -0.7874 0.4064)
			(end -0.7874 -0.4064)
			(stroke
				(width 0.1524)
				(type default)
			)
			(layer "F.SilkS")
		)
		(fp_line
			(start 0.7874 0.4064)
			(end -0.7874 0.4064)
			(stroke
				(width 0.1524)
				(type default)
			)
			(layer "F.SilkS")
		)
		(fp_line
			(start -0.7874 -0.4064)
			(end 0.7874 -0.4064)
			(stroke
				(width 0.1524)
				(type default)
			)
			(layer "F.SilkS")
		)
		(fp_line
			(start 0.7874 -0.4064)
			(end 0.7874 0.4064)
			(stroke
				(width 0.1524)
				(type default)
			)
			(layer "F.SilkS")
		)
		(fp_line
			(start -0.67945 0.3048)
			(end -0.67945 -0.305054)
			(stroke
				(width 0.1)
				(type default)
			)
			(layer "F.Fab")
		)
		(fp_line
			(start -0.12065 0.3048)
			(end -0.67945 0.3048)
			(stroke
				(width 0.1)
				(type default)
			)
			(layer "F.Fab")
		)
		(fp_line
			(start 0.120396 0.3048)
			(end 0.120396 0.2794)
			(stroke
				(width 0.1)
				(type default)
			)
			(layer "F.Fab")
		)
		(fp_line
			(start 0.67945 0.3048)
			(end 0.120396 0.3048)
			(stroke
				(width 0.1)
				(type default)
			)
			(layer "F.Fab")
		)
		(fp_line
			(start -0.12065 0.2794)
			(end -0.12065 0.3048)
			(stroke
				(width 0.1)
				(type default)
			)
			(layer "F.Fab")
		)
		(fp_line
			(start 0.120396 0.2794)
			(end -0.12065 0.2794)
			(stroke
				(width 0.1)
				(type default)
			)
			(layer "F.Fab")
		)
		(fp_line
			(start -0.12065 -0.2794)
			(end 0.12065 -0.2794)
			(stroke
				(width 0.1)
				(type default)
			)
			(layer "F.Fab")
		)
		(fp_line
			(start 0.12065 -0.2794)
			(end 0.12065 -0.3048)
			(stroke
				(width 0.1)
				(type default)
			)
			(layer "F.Fab")
		)
		(fp_line
			(start 0.12065 -0.3048)
			(end 0.67945 -0.3048)
			(stroke
				(width 0.1)
				(type default)
			)
			(layer "F.Fab")
		)
		(fp_line
			(start 0.67945 -0.3048)
			(end 0.67945 0.3048)
			(stroke
				(width 0.1)
				(type default)
			)
			(layer "F.Fab")
		)
		(fp_line
			(start -0.67945 -0.305054)
			(end -0.12065 -0.305054)
			(stroke
				(width 0.1)
				(type default)
			)
			(layer "F.Fab")
		)
		(fp_line
			(start -0.12065 -0.305054)
			(end -0.12065 -0.2794)
			(stroke
				(width 0.1)
				(type default)
			)
			(layer "F.Fab")
		)
		(pad "1" smd circle
			(at -0.40005 0 270)
			(size 0 0)
			(layers "F.Cu" "F.Mask" "F.Paste")
			(net "FM_BMC_PWRBTN_N")
		)
		(pad "2" smd circle
			(at 0.40005 0 270)
			(size 0 0)
			(layers "F.Cu" "F.Mask" "F.Paste")
			(net "P3V3_AUX")
		)
	)
	(footprint ""
		(layer "F.Cu")
		(at 103.198676 -79.078836)
		(property "Reference" "D93"
			(at -51.54041 38.649402 90)
			(unlocked yes)
			(layer "F.SilkS")
			(effects
				(font
					(size 0.635 0.4064)
					(thickness 0.1524)
				)
				(justify left)
			)
		)
		(property "Value" ""
			(at 0 0 0)
			(layer "F.Fab")
			(effects
				(font
					(size 1.27 1.27)
				)
			)
		)
		(duplicate_pad_numbers_are_jumpers no)
		(fp_line
			(start -0.90678 0.4826)
			(end -0.90678 -0.4699)
			(stroke
				(width 0.1524)
				(type default)
			)
			(layer "F.SilkS")
		)
		(fp_line
			(start -0.89408 -0.4826)
			(end 0.90678 -0.4826)
			(stroke
				(width 0.1524)
				(type default)
			)
			(layer "F.SilkS")
		)
		(fp_line
			(start -0.79248 -0.4826)
			(end 1.03378 -0.4826)
			(stroke
				(width 0.1524)
				(type default)
			)
			(layer "F.SilkS")
		)
		(fp_line
			(start -0.64008 -0.4826)
			(end 1.16078 -0.4826)
			(stroke
				(width 0.1524)
				(type default)
			)
			(layer "F.SilkS")
		)
		(fp_line
			(start 0.90678 -0.4826)
			(end 0.90678 0.4826)
			(stroke
				(width 0.1524)
				(type default)
			)
			(layer "F.SilkS")
		)
		(fp_line
			(start 0.90678 0.4826)
			(end -0.90678 0.4826)
			(stroke
				(width 0.1524)
				(type default)
			)
			(layer "F.SilkS")
		)
		(fp_line
			(start 1.03378 -0.4826)
			(end 1.03378 0.4826)
			(stroke
				(width 0.1524)
				(type default)
			)
			(layer "F.SilkS")
		)
		(fp_line
			(start 1.03378 0.4826)
			(end -0.79248 0.4826)
			(stroke
				(width 0.1524)
				(type default)
			)
			(layer "F.SilkS")
		)
		(fp_line
			(start 1.16078 -0.4826)
			(end 1.16078 0.4826)
			(stroke
				(width 0.1524)
				(type default)
			)
			(layer "F.SilkS")
		)
		(fp_line
			(start 1.16078 0.4826)
			(end -0.64008 0.4826)
			(stroke
				(width 0.1524)
				(type default)
			)
			(layer "F.SilkS")
		)
		(fp_line
			(start -0.499872 -0.249936)
			(end 0.499872 -0.249936)
			(stroke
				(width 0.1)
				(type default)
			)
			(layer "F.Fab")
		)
		(fp_line
			(start -0.499872 0.249936)
			(end -0.499872 -0.249936)
			(stroke
				(width 0.1)
				(type default)
			)
			(layer "F.Fab")
		)
		(fp_line
			(start 0.499872 -0.249936)
			(end 0.499872 0.249936)
			(stroke
				(width 0.1)
				(type default)
			)
			(layer "F.Fab")
		)
		(fp_line
			(start 0.499872 0.249936)
			(end -0.499872 0.249936)
			(stroke
				(width 0.1)
				(type default)
			)
			(layer "F.Fab")
		)
		(pad "A" smd rect
			(at -0.47498 0)
			(size 0.6096 0.7112)
			(layers "F.Cu" "F.Mask" "F.Paste")
			(net "LED_RST_RSMRST_PLD_R_N")
		)
		(pad "C" smd rect
			(at 0.47498 0)
			(size 0.6096 0.7112)
			(layers "F.Cu" "F.Mask" "F.Paste")
			(net "LED_RST_RSMRST_PLD_R_N_D")
		)
	)
)
